(kicad_pcb
	(version 20260206)
	(generator "pcbnew")
	(generator_version "10.0")
	(general
		(thickness 1.6)
		(legacy_teardrops no)
	)
	(paper "A4")
	(title_block
		(title "04192023_DAF0TMB3IC0_F0TG_MB_C_brd_V02_OCP.brd")
		(comment 1 "Grand Teton / footprints 1089-1094 of 8354")
	)
	(layers
		(0 "F.Cu" signal "TOP")
		(4 "In1.Cu" signal "GND")
		(6 "In2.Cu" signal "IN1")
		(8 "In3.Cu" signal "GND1")
		(10 "In4.Cu" signal "IN2")
		(12 "In5.Cu" signal "GND2")
		(14 "In6.Cu" signal "IN3")
		(16 "In7.Cu" signal "GND3")
		(18 "In8.Cu" signal "VCC")
		(20 "In9.Cu" signal "VCC1")
		(22 "In10.Cu" signal "GND4")
		(24 "In11.Cu" signal "IN4")
		(26 "In12.Cu" signal "GND5")
		(28 "In13.Cu" signal "IN5")
		(30 "In14.Cu" signal "GND6")
		(32 "In15.Cu" signal "IN6")
		(34 "In16.Cu" signal "GND7")
		(2 "B.Cu" signal "BOTTOM")
		(9 "F.Adhes" user "F.Adhesive")
		(11 "B.Adhes" user "B.Adhesive")
		(13 "F.Paste" user "Package Geometry/Pastemask Top")
		(15 "B.Paste" user "Package Geometry/Pastemask Bottom")
		(5 "F.SilkS" user "Ref Des/Silkscreen Top")
		(7 "B.SilkS" user "Ref Des/Silkscreen Bottom")
		(1 "F.Mask" user "Board Geometry/Soldermask Top")
		(3 "B.Mask" user "Board Geometry/Soldermask Bottom")
		(17 "Dwgs.User" user "User.Drawings")
		(19 "Cmts.User" user "User.Comments")
		(21 "Eco1.User" user "User.Eco1")
		(23 "Eco2.User" user "User.Eco2")
		(25 "Edge.Cuts" user "Board Geometry/Outline")
		(27 "Margin" user)
		(31 "F.CrtYd" user "Package Geometry/Place Bound Top")
		(29 "B.CrtYd" user "Package Geometry/Place Bound Bottom")
		(35 "F.Fab" user "Ref Des/Assembly Top")
		(33 "B.Fab" user "Ref Des/Assembly Bottom")
	)
	(footprint ""
		(layer "F.Cu")
		(at 336.172556 -137.25525)
		(property "Reference" "PC227"
			(at 0 0 0)
			(layer "F.SilkS")
			(hide yes)
			(effects
				(font
					(size 1.27 1.27)
				)
			)
		)
		(property "Value" ""
			(at 0 0 0)
			(layer "F.Fab")
			(effects
				(font
					(size 1.27 1.27)
				)
			)
		)
		(duplicate_pad_numbers_are_jumpers no)
		(fp_line
			(start -1.524 -0.762)
			(end 1.524 -0.762)
			(stroke
				(width 0.1524)
				(type default)
			)
			(layer "F.SilkS")
		)
		(fp_line
			(start -1.524 0.762)
			(end -1.524 -0.762)
			(stroke
				(width 0.1524)
				(type default)
			)
			(layer "F.SilkS")
		)
		(fp_line
			(start 1.524 -0.762)
			(end 1.524 0.762)
			(stroke
				(width 0.1524)
				(type default)
			)
			(layer "F.SilkS")
		)
		(fp_line
			(start 1.524 0.762)
			(end -1.524 0.762)
			(stroke
				(width 0.1524)
				(type default)
			)
			(layer "F.SilkS")
		)
		(fp_line
			(start -1.1049 -0.724916)
			(end -1.1049 0.724916)
			(stroke
				(width 0.1)
				(type default)
			)
			(layer "F.Fab")
		)
		(fp_line
			(start -1.1049 0.724916)
			(end 1.1049 0.724916)
			(stroke
				(width 0.1)
				(type default)
			)
			(layer "F.Fab")
		)
		(fp_line
			(start 1.1049 -0.724916)
			(end -1.1049 -0.724916)
			(stroke
				(width 0.1)
				(type default)
			)
			(layer "F.Fab")
		)
		(fp_line
			(start 1.1049 0.724916)
			(end 1.1049 -0.724916)
			(stroke
				(width 0.1)
				(type default)
			)
			(layer "F.Fab")
		)
		(pad "1" smd rect
			(at -0.889 0 180)
			(size 1.016 1.27)
			(layers "F.Cu" "F.Mask" "F.Paste")
			(net "SW_P12V_AUX_PVDD18_S5_P0_FLT")
		)
		(pad "2" smd rect
			(at 0.889 0 180)
			(size 1.016 1.27)
			(layers "F.Cu" "F.Mask" "F.Paste")
			(net "GND")
		)
	)
	(footprint ""
		(layer "F.Cu")
		(at 175.11776 -92.685616 90)
		(property "Reference" "R6743"
			(at 0 0 90)
			(layer "F.SilkS")
			(hide yes)
			(effects
				(font
					(size 1.27 1.27)
				)
			)
		)
		(property "Value" ""
			(at 0 0 90)
			(layer "F.Fab")
			(effects
				(font
					(size 1.27 1.27)
				)
			)
		)
		(duplicate_pad_numbers_are_jumpers no)
		(fp_line
			(start 0.7874 -0.4064)
			(end 0.7874 0.4064)
			(stroke
				(width 0.1524)
				(type default)
			)
			(layer "F.SilkS")
		)
		(fp_line
			(start -0.7874 -0.4064)
			(end 0.7874 -0.4064)
			(stroke
				(width 0.1524)
				(type default)
			)
			(layer "F.SilkS")
		)
		(fp_line
			(start 0.7874 0.4064)
			(end -0.7874 0.4064)
			(stroke
				(width 0.1524)
				(type default)
			)
			(layer "F.SilkS")
		)
		(fp_line
			(start -0.7874 0.4064)
			(end -0.7874 -0.4064)
			(stroke
				(width 0.1524)
				(type default)
			)
			(layer "F.SilkS")
		)
		(fp_line
			(start -0.12065 -0.305054)
			(end -0.12065 -0.2794)
			(stroke
				(width 0.1)
				(type default)
			)
			(layer "F.Fab")
		)
		(fp_line
			(start -0.67945 -0.305054)
			(end -0.12065 -0.305054)
			(stroke
				(width 0.1)
				(type default)
			)
			(layer "F.Fab")
		)
		(fp_line
			(start 0.67945 -0.3048)
			(end 0.67945 0.3048)
			(stroke
				(width 0.1)
				(type default)
			)
			(layer "F.Fab")
		)
		(fp_line
			(start 0.12065 -0.3048)
			(end 0.67945 -0.3048)
			(stroke
				(width 0.1)
				(type default)
			)
			(layer "F.Fab")
		)
		(fp_line
			(start 0.12065 -0.2794)
			(end 0.12065 -0.3048)
			(stroke
				(width 0.1)
				(type default)
			)
			(layer "F.Fab")
		)
		(fp_line
			(start -0.12065 -0.2794)
			(end 0.12065 -0.2794)
			(stroke
				(width 0.1)
				(type default)
			)
			(layer "F.Fab")
		)
		(fp_line
			(start 0.120396 0.2794)
			(end -0.12065 0.2794)
			(stroke
				(width 0.1)
				(type default)
			)
			(layer "F.Fab")
		)
		(fp_line
			(start -0.12065 0.2794)
			(end -0.12065 0.3048)
			(stroke
				(width 0.1)
				(type default)
			)
			(layer "F.Fab")
		)
		(fp_line
			(start 0.67945 0.3048)
			(end 0.120396 0.3048)
			(stroke
				(width 0.1)
				(type default)
			)
			(layer "F.Fab")
		)
		(fp_line
			(start 0.120396 0.3048)
			(end 0.120396 0.2794)
			(stroke
				(width 0.1)
				(type default)
			)
			(layer "F.Fab")
		)
		(fp_line
			(start -0.12065 0.3048)
			(end -0.67945 0.3048)
			(stroke
				(width 0.1)
				(type default)
			)
			(layer "F.Fab")
		)
		(fp_line
			(start -0.67945 0.3048)
			(end -0.67945 -0.305054)
			(stroke
				(width 0.1)
				(type default)
			)
			(layer "F.Fab")
		)
		(pad "1" smd circle
			(at -0.40005 0 90)
			(size 0 0)
			(layers "F.Cu" "F.Mask" "F.Paste")
			(net "P1V8_AUX")
		)
		(pad "2" smd circle
			(at 0.40005 0 90)
			(size 0 0)
			(layers "F.Cu" "F.Mask" "F.Paste")
			(net "RT_BOARD_ID_ID0")
		)
	)
	(footprint ""
		(layer "F.Cu")
		(at 225.171 -82.804)
		(property "Reference" "R8100"
			(at 0 0 0)
			(layer "F.SilkS")
			(hide yes)
			(effects
				(font
					(size 1.27 1.27)
				)
			)
		)
		(property "Value" ""
			(at 0 0 0)
			(layer "F.Fab")
			(effects
				(font
					(size 1.27 1.27)
				)
			)
		)
		(duplicate_pad_numbers_are_jumpers no)
		(fp_line
			(start -0.7874 -0.4064)
			(end 0.7874 -0.4064)
			(stroke
				(width 0.1524)
				(type default)
			)
			(layer "F.SilkS")
		)
		(fp_line
			(start -0.7874 0.4064)
			(end -0.7874 -0.4064)
			(stroke
				(width 0.1524)
				(type default)
			)
			(layer "F.SilkS")
		)
		(fp_line
			(start 0.7874 -0.4064)
			(end 0.7874 0.4064)
			(stroke
				(width 0.1524)
				(type default)
			)
			(layer "F.SilkS")
		)
		(fp_line
			(start 0.7874 0.4064)
			(end -0.7874 0.4064)
			(stroke
				(width 0.1524)
				(type default)
			)
			(layer "F.SilkS")
		)
		(fp_line
			(start -0.67945 -0.305054)
			(end -0.12065 -0.305054)
			(stroke
				(width 0.1)
				(type default)
			)
			(layer "F.Fab")
		)
		(fp_line
			(start -0.67945 0.3048)
			(end -0.67945 -0.305054)
			(stroke
				(width 0.1)
				(type default)
			)
			(layer "F.Fab")
		)
		(fp_line
			(start -0.12065 -0.305054)
			(end -0.12065 -0.2794)
			(stroke
				(width 0.1)
				(type default)
			)
			(layer "F.Fab")
		)
		(fp_line
			(start -0.12065 -0.2794)
			(end 0.12065 -0.2794)
			(stroke
				(width 0.1)
				(type default)
			)
			(layer "F.Fab")
		)
		(fp_line
			(start -0.12065 0.2794)
			(end -0.12065 0.3048)
			(stroke
				(width 0.1)
				(type default)
			)
			(layer "F.Fab")
		)
		(fp_line
			(start -0.12065 0.3048)
			(end -0.67945 0.3048)
			(stroke
				(width 0.1)
				(type default)
			)
			(layer "F.Fab")
		)
		(fp_line
			(start 0.120396 0.2794)
			(end -0.12065 0.2794)
			(stroke
				(width 0.1)
				(type default)
			)
			(layer "F.Fab")
		)
		(fp_line
			(start 0.120396 0.3048)
			(end 0.120396 0.2794)
			(stroke
				(width 0.1)
				(type default)
			)
			(layer "F.Fab")
		)
		(fp_line
			(start 0.12065 -0.3048)
			(end 0.67945 -0.3048)
			(stroke
				(width 0.1)
				(type default)
			)
			(layer "F.Fab")
		)
		(fp_line
			(start 0.12065 -0.2794)
			(end 0.12065 -0.3048)
			(stroke
				(width 0.1)
				(type default)
			)
			(layer "F.Fab")
		)
		(fp_line
			(start 0.67945 -0.3048)
			(end 0.67945 0.3048)
			(stroke
				(width 0.1)
				(type default)
			)
			(layer "F.Fab")
		)
		(fp_line
			(start 0.67945 0.3048)
			(end 0.120396 0.3048)
			(stroke
				(width 0.1)
				(type default)
			)
			(layer "F.Fab")
		)
		(pad "1" smd circle
			(at -0.40005 0)
			(size 0 0)
			(layers "F.Cu" "F.Mask" "F.Paste")
			(net "P3V3_E1S_PWRGD_0_R1")
		)
		(pad "2" smd circle
			(at 0.40005 0)
			(size 0 0)
			(layers "F.Cu" "F.Mask" "F.Paste")
			(net "P3V3_E1S_PWRGD_0_R")
		)
	)
	(footprint ""
		(layer "F.Cu")
		(at 38.443662 -429.790098 90)
		(property "Reference" "R4537"
			(at 0 0 90)
			(layer "F.SilkS")
			(hide yes)
			(effects
				(font
					(size 1.27 1.27)
				)
			)
		)
		(property "Value" ""
			(at 0 0 90)
			(layer "F.Fab")
			(effects
				(font
					(size 1.27 1.27)
				)
			)
		)
		(duplicate_pad_numbers_are_jumpers no)
		(fp_line
			(start 0.7874 -0.4064)
			(end 0.7874 0.4064)
			(stroke
				(width 0.1524)
				(type default)
			)
			(layer "F.SilkS")
		)
		(fp_line
			(start -0.7874 -0.4064)
			(end 0.7874 -0.4064)
			(stroke
				(width 0.1524)
				(type default)
			)
			(layer "F.SilkS")
		)
		(fp_line
			(start 0.7874 0.4064)
			(end -0.7874 0.4064)
			(stroke
				(width 0.1524)
				(type default)
			)
			(layer "F.SilkS")
		)
		(fp_line
			(start -0.7874 0.4064)
			(end -0.7874 -0.4064)
			(stroke
				(width 0.1524)
				(type default)
			)
			(layer "F.SilkS")
		)
		(fp_line
			(start -0.12065 -0.305054)
			(end -0.12065 -0.2794)
			(stroke
				(width 0.1)
				(type default)
			)
			(layer "F.Fab")
		)
		(fp_line
			(start -0.67945 -0.305054)
			(end -0.12065 -0.305054)
			(stroke
				(width 0.1)
				(type default)
			)
			(layer "F.Fab")
		)
		(fp_line
			(start 0.67945 -0.3048)
			(end 0.67945 0.3048)
			(stroke
				(width 0.1)
				(type default)
			)
			(layer "F.Fab")
		)
		(fp_line
			(start 0.12065 -0.3048)
			(end 0.67945 -0.3048)
			(stroke
				(width 0.1)
				(type default)
			)
			(layer "F.Fab")
		)
		(fp_line
			(start 0.12065 -0.2794)
			(end 0.12065 -0.3048)
			(stroke
				(width 0.1)
				(type default)
			)
			(layer "F.Fab")
		)
		(fp_line
			(start -0.12065 -0.2794)
			(end 0.12065 -0.2794)
			(stroke
				(width 0.1)
				(type default)
			)
			(layer "F.Fab")
		)
		(fp_line
			(start 0.120396 0.2794)
			(end -0.12065 0.2794)
			(stroke
				(width 0.1)
				(type default)
			)
			(layer "F.Fab")
		)
		(fp_line
			(start -0.12065 0.2794)
			(end -0.12065 0.3048)
			(stroke
				(width 0.1)
				(type default)
			)
			(layer "F.Fab")
		)
		(fp_line
			(start 0.67945 0.3048)
			(end 0.120396 0.3048)
			(stroke
				(width 0.1)
				(type default)
			)
			(layer "F.Fab")
		)
		(fp_line
			(start 0.120396 0.3048)
			(end 0.120396 0.2794)
			(stroke
				(width 0.1)
				(type default)
			)
			(layer "F.Fab")
		)
		(fp_line
			(start -0.12065 0.3048)
			(end -0.67945 0.3048)
			(stroke
				(width 0.1)
				(type default)
			)
			(layer "F.Fab")
		)
		(fp_line
			(start -0.67945 0.3048)
			(end -0.67945 -0.305054)
			(stroke
				(width 0.1)
				(type default)
			)
			(layer "F.Fab")
		)
		(pad "1" smd circle
			(at -0.40005 0 90)
			(size 0 0)
			(layers "F.Cu" "F.Mask" "F.Paste")
			(net "FM_P2E_EN_N")
		)
		(pad "2" smd circle
			(at 0.40005 0 90)
			(size 0 0)
			(layers "F.Cu" "F.Mask" "F.Paste")
			(net "CLK_GEN2_GPU_FPGA_OE_OR_N")
		)
	)
	(footprint ""
		(layer "F.Cu")
		(at 105.960164 -261.255256)
		(property "Reference" "C3911"
			(at 0 0 0)
			(layer "F.SilkS")
			(hide yes)
			(effects
				(font
					(size 1.27 1.27)
				)
			)
		)
		(property "Value" ""
			(at 0 0 0)
			(layer "F.Fab")
			(effects
				(font
					(size 1.27 1.27)
				)
			)
		)
		(duplicate_pad_numbers_are_jumpers no)
		(fp_line
			(start -0.7874 -0.4064)
			(end 0.7874 -0.4064)
			(stroke
				(width 0.1524)
				(type default)
			)
			(layer "F.SilkS")
		)
		(fp_line
			(start -0.7874 0.4064)
			(end -0.7874 -0.4064)
			(stroke
				(width 0.1524)
				(type default)
			)
			(layer "F.SilkS")
		)
		(fp_line
			(start 0.7874 -0.4064)
			(end 0.7874 0.4064)
			(stroke
				(width 0.1524)
				(type default)
			)
			(layer "F.SilkS")
		)
		(fp_line
			(start 0.7874 0.4064)
			(end -0.7874 0.4064)
			(stroke
				(width 0.1524)
				(type default)
			)
			(layer "F.SilkS")
		)
		(fp_line
			(start -0.67945 -0.305054)
			(end -0.12065 -0.305054)
			(stroke
				(width 0.1)
				(type default)
			)
			(layer "F.Fab")
		)
		(fp_line
			(start -0.67945 0.3048)
			(end -0.67945 -0.305054)
			(stroke
				(width 0.1)
				(type default)
			)
			(layer "F.Fab")
		)
		(fp_line
			(start -0.12065 -0.305054)
			(end -0.12065 -0.2794)
			(stroke
				(width 0.1)
				(type default)
			)
			(layer "F.Fab")
		)
		(fp_line
			(start -0.12065 -0.2794)
			(end 0.12065 -0.2794)
			(stroke
				(width 0.1)
				(type default)
			)
			(layer "F.Fab")
		)
		(fp_line
			(start -0.12065 0.2794)
			(end -0.12065 0.3048)
			(stroke
				(width 0.1)
				(type default)
			)
			(layer "F.Fab")
		)
		(fp_line
			(start -0.12065 0.3048)
			(end -0.67945 0.3048)
			(stroke
				(width 0.1)
				(type default)
			)
			(layer "F.Fab")
		)
		(fp_line
			(start 0.120396 0.2794)
			(end -0.12065 0.2794)
			(stroke
				(width 0.1)
				(type default)
			)
			(layer "F.Fab")
		)
		(fp_line
			(start 0.120396 0.3048)
			(end 0.120396 0.2794)
			(stroke
				(width 0.1)
				(type default)
			)
			(layer "F.Fab")
		)
		(fp_line
			(start 0.12065 -0.3048)
			(end 0.67945 -0.3048)
			(stroke
				(width 0.1)
				(type default)
			)
			(layer "F.Fab")
		)
		(fp_line
			(start 0.12065 -0.2794)
			(end 0.12065 -0.3048)
			(stroke
				(width 0.1)
				(type default)
			)
			(layer "F.Fab")
		)
		(fp_line
			(start 0.67945 -0.3048)
			(end 0.67945 0.3048)
			(stroke
				(width 0.1)
				(type default)
			)
			(layer "F.Fab")
		)
		(fp_line
			(start 0.67945 0.3048)
			(end 0.120396 0.3048)
			(stroke
				(width 0.1)
				(type default)
			)
			(layer "F.Fab")
		)
		(pad "1" smd circle
			(at -0.40005 0)
			(size 0 0)
			(layers "F.Cu" "F.Mask" "F.Paste")
			(net "PVDDIO_P1")
		)
		(pad "2" smd circle
			(at 0.40005 0)
			(size 0 0)
			(layers "F.Cu" "F.Mask" "F.Paste")
			(net "GND")
		)
	)
	(footprint ""
		(layer "F.Cu")
		(at 82.986118 -339.362796)
		(property "Reference" "PC375_1"
			(at 0 0 0)
			(layer "F.SilkS")
			(hide yes)
			(effects
				(font
					(size 1.27 1.27)
				)
			)
		)
		(property "Value" ""
			(at 0 0 0)
			(layer "F.Fab")
			(effects
				(font
					(size 1.27 1.27)
				)
			)
		)
		(duplicate_pad_numbers_are_jumpers no)
		(fp_line
			(start -0.7874 -0.4064)
			(end 0.7874 -0.4064)
			(stroke
				(width 0.1524)
				(type default)
			)
			(layer "F.SilkS")
		)
		(fp_line
			(start -0.7874 0.4064)
			(end -0.7874 -0.4064)
			(stroke
				(width 0.1524)
				(type default)
			)
			(layer "F.SilkS")
		)
		(fp_line
			(start 0.7874 -0.4064)
			(end 0.7874 0.4064)
			(stroke
				(width 0.1524)
				(type default)
			)
			(layer "F.SilkS")
		)
		(fp_line
			(start 0.7874 0.4064)
			(end -0.7874 0.4064)
			(stroke
				(width 0.1524)
				(type default)
			)
			(layer "F.SilkS")
		)
		(fp_line
			(start -0.67945 -0.305054)
			(end -0.12065 -0.305054)
			(stroke
				(width 0.1)
				(type default)
			)
			(layer "F.Fab")
		)
		(fp_line
			(start -0.67945 0.3048)
			(end -0.67945 -0.305054)
			(stroke
				(width 0.1)
				(type default)
			)
			(layer "F.Fab")
		)
		(fp_line
			(start -0.12065 -0.305054)
			(end -0.12065 -0.2794)
			(stroke
				(width 0.1)
				(type default)
			)
			(layer "F.Fab")
		)
		(fp_line
			(start -0.12065 -0.2794)
			(end 0.12065 -0.2794)
			(stroke
				(width 0.1)
				(type default)
			)
			(layer "F.Fab")
		)
		(fp_line
			(start -0.12065 0.2794)
			(end -0.12065 0.3048)
			(stroke
				(width 0.1)
				(type default)
			)
			(layer "F.Fab")
		)
		(fp_line
			(start -0.12065 0.3048)
			(end -0.67945 0.3048)
			(stroke
				(width 0.1)
				(type default)
			)
			(layer "F.Fab")
		)
		(fp_line
			(start 0.120396 0.2794)
			(end -0.12065 0.2794)
			(stroke
				(width 0.1)
				(type default)
			)
			(layer "F.Fab")
		)
		(fp_line
			(start 0.120396 0.3048)
			(end 0.120396 0.2794)
			(stroke
				(width 0.1)
				(type default)
			)
			(layer "F.Fab")
		)
		(fp_line
			(start 0.12065 -0.3048)
			(end 0.67945 -0.3048)
			(stroke
				(width 0.1)
				(type default)
			)
			(layer "F.Fab")
		)
		(fp_line
			(start 0.12065 -0.2794)
			(end 0.12065 -0.3048)
			(stroke
				(width 0.1)
				(type default)
			)
			(layer "F.Fab")
		)
		(fp_line
			(start 0.67945 -0.3048)
			(end 0.67945 0.3048)
			(stroke
				(width 0.1)
				(type default)
			)
			(layer "F.Fab")
		)
		(fp_line
			(start 0.67945 0.3048)
			(end 0.120396 0.3048)
			(stroke
				(width 0.1)
				(type default)
			)
			(layer "F.Fab")
		)
		(pad "1" smd circle
			(at -0.40005 0)
			(size 0 0)
			(layers "F.Cu" "F.Mask" "F.Paste")
			(net "SW_P12V_AUX_PVDDCR_CPU1_P1_FLT")
		)
		(pad "2" smd circle
			(at 0.40005 0)
			(size 0 0)
			(layers "F.Cu" "F.Mask" "F.Paste")
			(net "GND")
		)
	)
)
